# T6G (Grand Teton) — schematic netlist excerpt (pin names and nets, part order shuffled) for the footprints in the layout excerpt that follows; sources: Cadence DE-HDL packaged netlist, KiCad conversion of 04192023_DAF0TMB3IC0_F0TG_MB_C_brd_V02_OCP.brd

C1131  Q_CAP  0.1UF 16V 10% X7R  pkg C0402  page 83 : A = P1V8_AUX ; B = GND

X8026  TP_TDR_4P_FTS  TP_TDR_4P_DIP EMPTY  pkg TH  page 260
  S1  = TDR_DIFF_85_IN6_DP
  P1  = T1_GND
  P2  = T1_GND
  S2  = TDR_DIFF_85_IN6_DN

(kicad_pcb
	(version 20260206)
	(generator "pcbnew")
	(generator_version "10.0")
	(general
		(thickness 1.6)
		(legacy_teardrops no)
	)
	(paper "A4")
	(title_block
		(title "04192023_DAF0TMB3IC0_F0TG_MB_C_brd_V02_OCP.brd")
		(comment 1 "Grand Teton / footprints 6077-6078 of 8354")
	)
	(layers
		(0 "F.Cu" signal "TOP")
		(4 "In1.Cu" signal "GND")
		(6 "In2.Cu" signal "IN1")
		(8 "In3.Cu" signal "GND1")
		(10 "In4.Cu" signal "IN2")
		(12 "In5.Cu" signal "GND2")
		(14 "In6.Cu" signal "IN3")
		(16 "In7.Cu" signal "GND3")
		(18 "In8.Cu" signal "VCC")
		(20 "In9.Cu" signal "VCC1")
		(22 "In10.Cu" signal "GND4")
		(24 "In11.Cu" signal "IN4")
		(26 "In12.Cu" signal "GND5")
		(28 "In13.Cu" signal "IN5")
		(30 "In14.Cu" signal "GND6")
		(32 "In15.Cu" signal "IN6")
		(34 "In16.Cu" signal "GND7")
		(2 "B.Cu" signal "BOTTOM")
		(9 "F.Adhes" user "F.Adhesive")
		(11 "B.Adhes" user "B.Adhesive")
		(13 "F.Paste" user "Package Geometry/Pastemask Top")
		(15 "B.Paste" user "Package Geometry/Pastemask Bottom")
		(5 "F.SilkS" user "Ref Des/Silkscreen Top")
		(7 "B.SilkS" user "Ref Des/Silkscreen Bottom")
		(1 "F.Mask" user "Board Geometry/Soldermask Top")
		(3 "B.Mask" user "Board Geometry/Soldermask Bottom")
		(17 "Dwgs.User" user "User.Drawings")
		(19 "Cmts.User" user "User.Comments")
		(21 "Eco1.User" user "User.Eco1")
		(23 "Eco2.User" user "User.Eco2")
		(25 "Edge.Cuts" user "Board Geometry/Outline")
		(27 "Margin" user)
		(31 "F.CrtYd" user "Package Geometry/Place Bound Top")
		(29 "B.CrtYd" user "Package Geometry/Place Bound Bottom")
		(35 "F.Fab" user "Ref Des/Assembly Top")
		(33 "B.Fab" user "Ref Des/Assembly Bottom")
	)
	(footprint ""
		(layer "B.Cu")
		(at 493.36833 7.564882 90)
		(property "Reference" "X8026"
			(at 0.93726 -1.53035 270)
			(unlocked yes)
			(layer "B.SilkS")
			(effects
				(font
					(size 0.7874 0.5842)
					(thickness 0.1524)
				)
				(justify left mirror)
			)
		)
		(property "Value" ""
			(at 0 0 90)
			(layer "B.Fab")
			(effects
				(font
					(size 1.27 1.27)
				)
				(justify mirror)
			)
		)
		(property "Device Type" "TP_TDR_4P_FTS_TH-TP_TDR_4P_DIP,EMPTY,TP15"
			(at -1.30175 1.27 0)
			(unlocked yes)
			(layer "B.Fab")
			(hide yes)
			(effects
				(font
					(size 0.635 0.4064)
					(thickness 0.1524)
				)
				(justify mirror)
			)
		)
		(property "User Part Number" "N_A"
			(at -1.30175 1.27 0)
			(unlocked yes)
			(layer "Cmts.User")
			(hide yes)
			(effects
				(font
					(size 0.635 0.4064)
					(thickness 0.1524)
				)
				(justify mirror)
			)
		)
		(duplicate_pad_numbers_are_jumpers no)
		(fp_line
			(start 0 -1.27)
			(end 0 -0.635)
			(stroke
				(width 0.1524)
				(type default)
			)
			(layer "B.SilkS")
		)
		(fp_line
			(start -2.54 -1.27)
			(end 0 -1.27)
			(stroke
				(width 0.1524)
				(type default)
			)
			(layer "B.SilkS")
		)
		(fp_line
			(start -2.54 -1.1303)
			(end -2.54 -1.27)
			(stroke
				(width 0.1524)
				(type default)
			)
			(layer "B.SilkS")
		)
		(fp_line
			(start 0 0.635)
			(end 0 1.905)
			(stroke
				(width 0.1524)
				(type default)
			)
			(layer "B.SilkS")
		)
		(fp_line
			(start -2.54 1.4097)
			(end -2.54 1.1303)
			(stroke
				(width 0.1524)
				(type default)
			)
			(layer "B.SilkS")
		)
		(fp_line
			(start 0 3.175)
			(end 0 3.81)
			(stroke
				(width 0.1524)
				(type default)
			)
			(layer "B.SilkS")
		)
		(fp_line
			(start 0 3.81)
			(end -2.54 3.81)
			(stroke
				(width 0.1524)
				(type default)
			)
			(layer "B.SilkS")
		)
		(fp_line
			(start -2.54 3.81)
			(end -2.54 3.6703)
			(stroke
				(width 0.1524)
				(type default)
			)
			(layer "B.SilkS")
		)
		(fp_poly
			(pts
				(xy 0.761746 0) (xy 2.285746 -0.762) (xy 2.285746 0.762)
			)
			(stroke
				(width 0)
				(type default)
			)
			(fill yes)
			(layer "B.SilkS")
		)
		(fp_line
			(start 0 -1.27)
			(end 0 3.81)
			(stroke
				(width 0.1)
				(type default)
			)
			(layer "B.Fab")
		)
		(fp_line
			(start -2.54 -1.27)
			(end 0 -1.27)
			(stroke
				(width 0.1)
				(type default)
			)
			(layer "B.Fab")
		)
		(fp_line
			(start 0 3.81)
			(end -2.54 3.81)
			(stroke
				(width 0.1)
				(type default)
			)
			(layer "B.Fab")
		)
		(fp_line
			(start -2.54 3.81)
			(end -2.54 -1.27)
			(stroke
				(width 0.1)
				(type default)
			)
			(layer "B.Fab")
		)
		(fp_poly
			(pts
				(xy 0.761746 0) (xy 2.285746 -0.762) (xy 2.285746 0.762)
			)
			(stroke
				(width 0)
				(type default)
			)
			(fill yes)
			(layer "B.Fab")
		)
		(pad "1" thru_hole circle
			(at 0 0 270)
			(size 1.0033 1.0033)
			(drill 0.249936)
			(layers "*.Cu" "*.Mask")
			(remove_unused_layers no)
			(net "TDR_DIFF_85_IN6_DP")
			(clearance 0.10795)
			(padstack
				(mode front_inner_back)
				(layer "Inner"
					(shape circle)
					(size 0.8001 0.8001)
					(clearance 0.1524)
				)
				(layer "B.Cu"
					(shape circle)
					(size 1.0033 1.0033)
					(thermal_gap 0.10795)
					(clearance 0.10795)
				)
			)
		)
		(pad "2" thru_hole circle
			(at -2.54 0 270)
			(size 1.9939 1.9939)
			(drill 0.249936)
			(layers "*.Cu" "*.Mask")
			(remove_unused_layers no)
			(net "T1_GND")
			(clearance 0.10795)
			(padstack
				(mode front_inner_back)
				(layer "Inner"
					(shape circle)
					(size 0.8001 0.8001)
					(clearance 0.1524)
				)
				(layer "B.Cu"
					(shape circle)
					(size 1.9939 1.9939)
					(thermal_gap 0.10795)
					(clearance 0.10795)
				)
			)
		)
		(pad "3" thru_hole circle
			(at -2.54 2.54 270)
			(size 1.9939 1.9939)
			(drill 0.249936)
			(layers "*.Cu" "*.Mask")
			(remove_unused_layers no)
			(net "T1_GND")
			(clearance 0.10795)
			(padstack
				(mode front_inner_back)
				(layer "Inner"
					(shape circle)
					(size 0.8001 0.8001)
					(clearance 0.1524)
				)
				(layer "B.Cu"
					(shape circle)
					(size 1.9939 1.9939)
					(thermal_gap 0.10795)
					(clearance 0.10795)
				)
			)
		)
		(pad "4" thru_hole circle
			(at 0 2.54 270)
			(size 1.0033 1.0033)
			(drill 0.249936)
			(layers "*.Cu" "*.Mask")
			(remove_unused_layers no)
			(net "TDR_DIFF_85_IN6_DN")
			(clearance 0.10795)
			(padstack
				(mode front_inner_back)
				(layer "Inner"
					(shape circle)
					(size 0.8001 0.8001)
					(clearance 0.1524)
				)
				(layer "B.Cu"
					(shape circle)
					(size 1.0033 1.0033)
					(thermal_gap 0.10795)
					(clearance 0.10795)
				)
			)
		)
	)
	(footprint ""
		(layer "B.Cu")
		(at 184.332372 -111.863124 -90)
		(property "Reference" "C1131"
			(at 0 0 90)
			(layer "B.SilkS")
			(hide yes)
			(effects
				(font
					(size 1.27 1.27)
				)
				(justify mirror)
			)
		)
		(property "Value" ""
			(at 0 0 90)
			(layer "B.Fab")
			(effects
				(font
					(size 1.27 1.27)
				)
				(justify mirror)
			)
		)
		(duplicate_pad_numbers_are_jumpers no)
		(fp_line
			(start -0.69215 0.2921)
			(end 0.69215 0.2921)
			(stroke
				(width 0.1524)
				(type default)
			)
			(layer "B.SilkS")
		)
		(fp_line
			(start 0.69215 0.2921)
			(end 0.69215 -0.2921)
			(stroke
				(width 0.1524)
				(type default)
			)
			(layer "B.SilkS")
		)
		(fp_line
			(start -0.69215 -0.2921)
			(end -0.69215 0.2921)
			(stroke
				(width 0.1524)
				(type default)
			)
			(layer "B.SilkS")
		)
		(fp_line
			(start 0.69215 -0.2921)
			(end -0.69215 -0.2921)
			(stroke
				(width 0.1524)
				(type default)
			)
			(layer "B.SilkS")
		)
		(fp_line
			(start -0.51435 0.2794)
			(end 0.51435 0.2794)
			(stroke
				(width 0.1)
				(type default)
			)
			(layer "B.Fab")
		)
		(fp_line
			(start 0.51435 0.2794)
			(end 0.51435 -0.2794)
			(stroke
				(width 0.1)
				(type default)
			)
			(layer "B.Fab")
		)
		(fp_line
			(start -0.51435 -0.2794)
			(end -0.51435 0.2794)
			(stroke
				(width 0.1)
				(type default)
			)
			(layer "B.Fab")
		)
		(fp_line
			(start 0.51435 -0.2794)
			(end -0.51435 -0.2794)
			(stroke
				(width 0.1)
				(type default)
			)
			(layer "B.Fab")
		)
		(pad "1" smd circle
			(at 0.40005 0 90)
			(size 0 0)
			(layers "B.Cu" "B.Mask" "B.Paste")
			(net "P1V8_AUX")
		)
		(pad "2" smd circle
			(at -0.40005 0 90)
			(size 0 0)
			(layers "B.Cu" "B.Mask" "B.Paste")
			(net "GND")
		)
		(zone
			(layer "B.Cu")
			(hatch none 0.5)
			(connect_pads
				(clearance 0)
			)
			(min_thickness 0.25)
			(keepout
				(tracks not_allowed)
				(vias allowed)
				(pads allowed)
				(copperpour not_allowed)
				(footprints allowed)
			)
			(placement
				(enabled no)
				(sheetname "")
			)
			(fill
				(thermal_gap 0.5)
				(thermal_bridge_width 0.5)
				(island_removal_mode 0)
			)
			(polygon
				(pts
					(xy 184.186576 -111.764064) (xy 184.186576 -111.963454) (xy 184.244742 -112.053624) (xy 184.420002 -112.053624)
					(xy 184.478422 -111.963454) (xy 184.478422 -111.764064) (xy 184.420256 -111.672624) (xy 184.244742 -111.672624)
				)
			)
		)
	)
)
